FILE_TYPE=LIBRARY_PARTS;
primitive 'BC847BPN';
  pin
    'B1':
      PIN_NUMBER='(2,0)';
      INPUT_LOAD='(-0.01,0.01)';
    'C1':
      PIN_NUMBER='(6,0)';
      BIDIRECTIONAL='TRUE';
      INPUT_LOAD='(-0.01,0.01)';
      OUTPUT_LOAD='(1.0,-1.0)';
    'E1':
      PIN_NUMBER='(1,0)';
      BIDIRECTIONAL='TRUE';
      INPUT_LOAD='(-0.01,0.01)';
      OUTPUT_LOAD='(1.0,-1.0)';
    'B2':
      PIN_NUMBER='(0,5)';
      INPUT_LOAD='(-0.01,0.01)';
    'C2':
      PIN_NUMBER='(0,3)';
      BIDIRECTIONAL='TRUE';
      INPUT_LOAD='(-0.01,0.01)';
      OUTPUT_LOAD='(1.0,-1.0)';
    'E2':
      PIN_NUMBER='(0,4)';
      BIDIRECTIONAL='TRUE';
      INPUT_LOAD='(-0.01,0.01)';
      OUTPUT_LOAD='(1.0,-1.0)';
  end_pin;
  body
    PART_NAME='BC847BPN';
    BODY_NAME='BC847BPN';
    PHYS_DES_PREFIX='Q';
    CLASS='DISCRETE';
  end_body;
end_primitive;

END.
